FILE_TYPE = MACRO_DRAWING;
SET COLOR_WIRE YELLOW;
SET COLOR_PROP ORANGE;
SET COLOR_DOT WHITE;
SET COLOR_ARC YELLOW;
SET COLOR_BODY GREEN;
SET COLOR_NOTE PURPLE;
SET PROP_DISPLAY VALUE;
SET PAGE_NUMBER P59;
FORCEADD TAP..1
R 2
(-725 3325);
FORCEPROP 3 LASTPIN (-675 3325) SIG_NAME TP_DMI_CPU1_PCH_RX_C_DN<6>
J 0
(-665 3335);
DISPLAY 0.659574 (-665 3335);
PAINT MONO (-665 3335);
DISPLAY INVISIBLE (-665 3335);
FORCEPROP 1 LASTPIN (-675 3325) BN 6
J 2
(-663 3333);
DISPLAY 0.680851 (-663 3333);
PAINT GREEN (-663 3333);
FORCEPROP 2 LAST CDS_LIB standard
J 0
(-725 3325);
DISPLAY INVISIBLE (-725 3325);
FORCEPROP 1 LAST BODY_TYPE PLUMBING
J 2
(-725 3375);
DISPLAY 0.872340 (-725 3375);
PAINT GREEN (-725 3375);
DISPLAY INVISIBLE (-725 3375);
FORCEPROP 1 LAST HDL_TAP TRUE
J 2
(-1050 3200);
DISPLAY 0.872340 (-1050 3200);
DISPLAY INVISIBLE (-1050 3200);
FORCEPROP 1 LAST PATH I10
J 2
(-723 3325);
DISPLAY 0.872340 (-723 3325);
PAINT GREEN (-723 3325);
DISPLAY INVISIBLE (-723 3325);
FORCEADD TAP..1
R 2
(-725 3275);
FORCEPROP 3 LASTPIN (-675 3275) SIG_NAME TP_DMI_CPU1_PCH_RX_C_DN<5>
J 0
(-665 3285);
DISPLAY 0.659574 (-665 3285);
PAINT MONO (-665 3285);
DISPLAY INVISIBLE (-665 3285);
FORCEPROP 1 LASTPIN (-675 3275) BN 5
J 2
(-663 3283);
DISPLAY 0.680851 (-663 3283);
PAINT GREEN (-663 3283);
FORCEPROP 2 LAST CDS_LIB standard
J 0
(-725 3275);
DISPLAY INVISIBLE (-725 3275);
FORCEPROP 1 LAST BODY_TYPE PLUMBING
J 2
(-725 3325);
DISPLAY 0.872340 (-725 3325);
PAINT GREEN (-725 3325);
DISPLAY INVISIBLE (-725 3325);
FORCEPROP 1 LAST HDL_TAP TRUE
J 2
(-1050 3150);
DISPLAY 0.872340 (-1050 3150);
DISPLAY INVISIBLE (-1050 3150);
FORCEPROP 1 LAST PATH I11
J 2
(-723 3275);
DISPLAY 0.872340 (-723 3275);
PAINT GREEN (-723 3275);
DISPLAY INVISIBLE (-723 3275);
FORCEADD TAP..1
R 2
(-725 3625);
FORCEPROP 3 LASTPIN (-675 3625) SIG_NAME TP_DMI_CPU1_PCH_RX_C_DP<3>
J 0
(-665 3635);
DISPLAY 0.659574 (-665 3635);
PAINT MONO (-665 3635);
DISPLAY INVISIBLE (-665 3635);
FORCEPROP 1 LASTPIN (-675 3625) BN 3
J 2
(-663 3633);
DISPLAY 0.680851 (-663 3633);
PAINT GREEN (-663 3633);
FORCEPROP 2 LAST CDS_LIB standard
J 0
(-725 3625);
DISPLAY INVISIBLE (-725 3625);
FORCEPROP 1 LAST BODY_TYPE PLUMBING
J 2
(-725 3675);
DISPLAY 0.872340 (-725 3675);
PAINT GREEN (-725 3675);
DISPLAY INVISIBLE (-725 3675);
FORCEPROP 1 LAST HDL_TAP TRUE
J 2
(-1050 3500);
DISPLAY 0.872340 (-1050 3500);
DISPLAY INVISIBLE (-1050 3500);
FORCEPROP 1 LAST PATH I12
J 2
(-723 3625);
DISPLAY 0.872340 (-723 3625);
PAINT GREEN (-723 3625);
DISPLAY INVISIBLE (-723 3625);
FORCEADD TAP..1
R 2
(-725 3575);
FORCEPROP 3 LASTPIN (-675 3575) SIG_NAME TP_DMI_CPU1_PCH_RX_C_DP<2>
J 0
(-665 3585);
DISPLAY 0.659574 (-665 3585);
PAINT MONO (-665 3585);
DISPLAY INVISIBLE (-665 3585);
FORCEPROP 1 LASTPIN (-675 3575) BN 2
J 2
(-663 3583);
DISPLAY 0.680851 (-663 3583);
PAINT GREEN (-663 3583);
FORCEPROP 2 LAST CDS_LIB standard
J 0
(-725 3575);
DISPLAY INVISIBLE (-725 3575);
FORCEPROP 1 LAST BODY_TYPE PLUMBING
J 2
(-725 3625);
DISPLAY 0.872340 (-725 3625);
PAINT GREEN (-725 3625);
DISPLAY INVISIBLE (-725 3625);
FORCEPROP 1 LAST HDL_TAP TRUE
J 2
(-1050 3450);
DISPLAY 0.872340 (-1050 3450);
DISPLAY INVISIBLE (-1050 3450);
FORCEPROP 1 LAST PATH I13
J 2
(-723 3575);
DISPLAY 0.872340 (-723 3575);
PAINT GREEN (-723 3575);
DISPLAY INVISIBLE (-723 3575);
FORCEADD TAP..1
R 2
(-725 3475);
FORCEPROP 3 LASTPIN (-675 3475) SIG_NAME TP_DMI_CPU1_PCH_RX_C_DP<0>
J 0
(-665 3485);
DISPLAY 0.659574 (-665 3485);
PAINT MONO (-665 3485);
DISPLAY INVISIBLE (-665 3485);
FORCEPROP 1 LASTPIN (-675 3475) BN 0
J 2
(-663 3483);
DISPLAY 0.680851 (-663 3483);
PAINT GREEN (-663 3483);
FORCEPROP 2 LAST CDS_LIB standard
J 0
(-725 3475);
DISPLAY INVISIBLE (-725 3475);
FORCEPROP 1 LAST BODY_TYPE PLUMBING
J 2
(-725 3525);
DISPLAY 0.872340 (-725 3525);
PAINT GREEN (-725 3525);
DISPLAY INVISIBLE (-725 3525);
FORCEPROP 1 LAST HDL_TAP TRUE
J 2
(-1050 3350);
DISPLAY 0.872340 (-1050 3350);
DISPLAY INVISIBLE (-1050 3350);
FORCEPROP 1 LAST PATH I14
J 2
(-723 3475);
DISPLAY 0.872340 (-723 3475);
PAINT GREEN (-723 3475);
DISPLAY INVISIBLE (-723 3475);
FORCEADD TAP..1
R 2
(-725 3525);
FORCEPROP 3 LASTPIN (-675 3525) SIG_NAME TP_DMI_CPU1_PCH_RX_C_DP<1>
J 0
(-665 3535);
DISPLAY 0.659574 (-665 3535);
PAINT MONO (-665 3535);
DISPLAY INVISIBLE (-665 3535);
FORCEPROP 1 LASTPIN (-675 3525) BN 1
J 2
(-663 3533);
DISPLAY 0.680851 (-663 3533);
PAINT GREEN (-663 3533);
FORCEPROP 2 LAST CDS_LIB standard
J 0
(-725 3525);
DISPLAY INVISIBLE (-725 3525);
FORCEPROP 1 LAST BODY_TYPE PLUMBING
J 2
(-725 3575);
DISPLAY 0.872340 (-725 3575);
PAINT GREEN (-725 3575);
DISPLAY INVISIBLE (-725 3575);
FORCEPROP 1 LAST HDL_TAP TRUE
J 2
(-1050 3400);
DISPLAY 0.872340 (-1050 3400);
DISPLAY INVISIBLE (-1050 3400);
FORCEPROP 1 LAST PATH I15
J 2
(-723 3525);
DISPLAY 0.872340 (-723 3525);
PAINT GREEN (-723 3525);
DISPLAY INVISIBLE (-723 3525);
FORCEADD TAP..1
R 2
(-725 3825);
FORCEPROP 3 LASTPIN (-675 3825) SIG_NAME TP_DMI_CPU1_PCH_RX_C_DP<7>
J 0
(-665 3835);
DISPLAY 0.659574 (-665 3835);
PAINT MONO (-665 3835);
DISPLAY INVISIBLE (-665 3835);
FORCEPROP 1 LASTPIN (-675 3825) BN 7
J 2
(-663 3833);
DISPLAY 0.680851 (-663 3833);
PAINT GREEN (-663 3833);
FORCEPROP 2 LAST CDS_LIB standard
J 0
(-725 3825);
DISPLAY INVISIBLE (-725 3825);
FORCEPROP 1 LAST BODY_TYPE PLUMBING
J 2
(-725 3875);
DISPLAY 0.872340 (-725 3875);
PAINT GREEN (-725 3875);
DISPLAY INVISIBLE (-725 3875);
FORCEPROP 1 LAST HDL_TAP TRUE
J 2
(-1050 3700);
DISPLAY 0.872340 (-1050 3700);
DISPLAY INVISIBLE (-1050 3700);
FORCEPROP 1 LAST PATH I16
J 2
(-723 3825);
DISPLAY 0.872340 (-723 3825);
PAINT GREEN (-723 3825);
DISPLAY INVISIBLE (-723 3825);
FORCEADD TAP..1
R 2
(-725 3775);
FORCEPROP 3 LASTPIN (-675 3775) SIG_NAME TP_DMI_CPU1_PCH_RX_C_DP<6>
J 0
(-665 3785);
DISPLAY 0.659574 (-665 3785);
PAINT MONO (-665 3785);
DISPLAY INVISIBLE (-665 3785);
FORCEPROP 1 LASTPIN (-675 3775) BN 6
J 2
(-663 3783);
DISPLAY 0.680851 (-663 3783);
PAINT GREEN (-663 3783);
FORCEPROP 2 LAST CDS_LIB standard
J 0
(-725 3775);
DISPLAY INVISIBLE (-725 3775);
FORCEPROP 1 LAST BODY_TYPE PLUMBING
J 2
(-725 3825);
DISPLAY 0.872340 (-725 3825);
PAINT GREEN (-725 3825);
DISPLAY INVISIBLE (-725 3825);
FORCEPROP 1 LAST HDL_TAP TRUE
J 2
(-1050 3650);
DISPLAY 0.872340 (-1050 3650);
DISPLAY INVISIBLE (-1050 3650);
FORCEPROP 1 LAST PATH I17
J 2
(-723 3775);
DISPLAY 0.872340 (-723 3775);
PAINT GREEN (-723 3775);
DISPLAY INVISIBLE (-723 3775);
FORCEADD TAP..1
R 2
(-725 3675);
FORCEPROP 3 LASTPIN (-675 3675) SIG_NAME TP_DMI_CPU1_PCH_RX_C_DP<4>
J 0
(-665 3685);
DISPLAY 0.659574 (-665 3685);
PAINT MONO (-665 3685);
DISPLAY INVISIBLE (-665 3685);
FORCEPROP 1 LASTPIN (-675 3675) BN 4
J 2
(-663 3683);
DISPLAY 0.680851 (-663 3683);
PAINT GREEN (-663 3683);
FORCEPROP 2 LAST CDS_LIB standard
J 0
(-725 3675);
DISPLAY INVISIBLE (-725 3675);
FORCEPROP 1 LAST BODY_TYPE PLUMBING
J 2
(-725 3725);
DISPLAY 0.872340 (-725 3725);
PAINT GREEN (-725 3725);
DISPLAY INVISIBLE (-725 3725);
FORCEPROP 1 LAST HDL_TAP TRUE
J 2
(-1050 3550);
DISPLAY 0.872340 (-1050 3550);
DISPLAY INVISIBLE (-1050 3550);
FORCEPROP 1 LAST PATH I18
J 2
(-723 3675);
DISPLAY 0.872340 (-723 3675);
PAINT GREEN (-723 3675);
DISPLAY INVISIBLE (-723 3675);
FORCEADD TAP..1
R 2
(-725 3725);
FORCEPROP 3 LASTPIN (-675 3725) SIG_NAME TP_DMI_CPU1_PCH_RX_C_DP<5>
J 0
(-665 3735);
DISPLAY 0.659574 (-665 3735);
PAINT MONO (-665 3735);
DISPLAY INVISIBLE (-665 3735);
FORCEPROP 1 LASTPIN (-675 3725) BN 5
J 2
(-663 3733);
DISPLAY 0.680851 (-663 3733);
PAINT GREEN (-663 3733);
FORCEPROP 2 LAST CDS_LIB standard
J 0
(-725 3725);
DISPLAY INVISIBLE (-725 3725);
FORCEPROP 1 LAST BODY_TYPE PLUMBING
J 2
(-725 3775);
DISPLAY 0.872340 (-725 3775);
PAINT GREEN (-725 3775);
DISPLAY INVISIBLE (-725 3775);
FORCEPROP 1 LAST HDL_TAP TRUE
J 2
(-1050 3600);
DISPLAY 0.872340 (-1050 3600);
DISPLAY INVISIBLE (-1050 3600);
FORCEPROP 1 LAST PATH I19
J 2
(-723 3725);
DISPLAY 0.872340 (-723 3725);
PAINT GREEN (-723 3725);
DISPLAY INVISIBLE (-723 3725);
FORCEADD SOCKET4677_AZIF0045P001C01CS..16
(975 3425);
FORCEPROP 1 LAST PART_NUMBER DGA^7000023
J 0
(-75 4075);
DISPLAY 0.723404 (-75 4075);
PAINT GREEN (-75 4075);
DISPLAY INVISIBLE (-75 4075);
FORCEPROP 2 LAST VALUE SOCKET4677_AZIF0045-P001C01CS
J 0
(-75 4200);
DISPLAY 1.021277 (-75 4200);
FORCEPROP 1 LAST MATERIAL IO
J 0
(-75 4000);
DISPLAY 0.723404 (-75 4000);
PAINT GREEN (-75 4000);
FORCEPROP 2 LAST PART_TYPE SMLF
J 0
(-75 4250);
DISPLAY 1.021277 (-75 4250);
FORCEPROP 1 LAST $LOCATION U1
J 0
(-75 4150);
DISPLAY 0.723404 (-75 4150);
PAINT GREEN (-75 4150);
FORCEPROP 0 LASTPIN (-225 3025) $PN BB18
J 2
(-235 3035);
DISPLAY 0.680851 (-235 3035);
PAINT MONO (-235 3035);
FORCEPROP 0 LASTPIN (-225 3075) $PN BE17
J 2
(-235 3085);
DISPLAY 0.680851 (-235 3085);
PAINT MONO (-235 3085);
FORCEPROP 0 LASTPIN (-225 3125) $PN BF18
J 2
(-235 3135);
DISPLAY 0.680851 (-235 3135);
PAINT MONO (-235 3135);
FORCEPROP 0 LASTPIN (-225 3175) $PN BJ17
J 2
(-235 3185);
DISPLAY 0.680851 (-235 3185);
PAINT MONO (-235 3185);
FORCEPROP 0 LASTPIN (-225 3225) $PN BK18
J 2
(-235 3235);
DISPLAY 0.680851 (-235 3235);
PAINT MONO (-235 3235);
FORCEPROP 0 LASTPIN (-225 3275) $PN BN17
J 2
(-235 3285);
DISPLAY 0.680851 (-235 3285);
PAINT MONO (-235 3285);
FORCEPROP 0 LASTPIN (-225 3325) $PN BP18
J 2
(-235 3335);
DISPLAY 0.680851 (-235 3335);
PAINT MONO (-235 3335);
FORCEPROP 0 LASTPIN (-225 3375) $PN BU17
J 2
(-235 3385);
DISPLAY 0.680851 (-235 3385);
PAINT MONO (-235 3385);
FORCEPROP 0 LASTPIN (-225 3475) $PN BC19
J 2
(-235 3485);
DISPLAY 0.680851 (-235 3485);
PAINT MONO (-235 3485);
FORCEPROP 0 LASTPIN (-225 3525) $PN BD18
J 2
(-235 3535);
DISPLAY 0.680851 (-235 3535);
PAINT MONO (-235 3535);
FORCEPROP 0 LASTPIN (-225 3575) $PN BG19
J 2
(-235 3585);
DISPLAY 0.680851 (-235 3585);
PAINT MONO (-235 3585);
FORCEPROP 0 LASTPIN (-225 3625) $PN BH18
J 2
(-235 3635);
DISPLAY 0.680851 (-235 3635);
PAINT MONO (-235 3635);
FORCEPROP 0 LASTPIN (-225 3675) $PN BL19
J 2
(-235 3685);
DISPLAY 0.680851 (-235 3685);
PAINT MONO (-235 3685);
FORCEPROP 0 LASTPIN (-225 3725) $PN BM18
J 2
(-235 3735);
DISPLAY 0.680851 (-235 3735);
PAINT MONO (-235 3735);
FORCEPROP 0 LASTPIN (-225 3775) $PN BR19
J 2
(-235 3785);
DISPLAY 0.680851 (-235 3785);
PAINT MONO (-235 3785);
FORCEPROP 0 LASTPIN (-225 3825) $PN BT18
J 2
(-235 3835);
DISPLAY 0.680851 (-235 3835);
PAINT MONO (-235 3835);
FORCEPROP 0 LASTPIN (2175 3025) $PN BW19
J 0
(2185 3035);
DISPLAY 0.680851 (2185 3035);
PAINT MONO (2185 3035);
FORCEPROP 0 LASTPIN (2175 3075) $PN CA17
J 0
(2185 3085);
DISPLAY 0.680851 (2185 3085);
PAINT MONO (2185 3085);
FORCEPROP 0 LASTPIN (2175 3125) $PN CB18
J 0
(2185 3135);
DISPLAY 0.680851 (2185 3135);
PAINT MONO (2185 3135);
FORCEPROP 0 LASTPIN (2175 3175) $PN CE17
J 0
(2185 3185);
DISPLAY 0.680851 (2185 3185);
PAINT MONO (2185 3185);
FORCEPROP 0 LASTPIN (2175 3225) $PN CF18
J 0
(2185 3235);
DISPLAY 0.680851 (2185 3235);
PAINT MONO (2185 3235);
FORCEPROP 0 LASTPIN (2175 3275) $PN CJ17
J 0
(2185 3285);
DISPLAY 0.680851 (2185 3285);
PAINT MONO (2185 3285);
FORCEPROP 0 LASTPIN (2175 3325) $PN CK18
J 0
(2185 3335);
DISPLAY 0.680851 (2185 3335);
PAINT MONO (2185 3335);
FORCEPROP 0 LASTPIN (2175 3375) $PN CN17
J 0
(2185 3385);
DISPLAY 0.680851 (2185 3385);
PAINT MONO (2185 3385);
FORCEPROP 0 LASTPIN (2175 3475) $PN CA19
J 0
(2185 3485);
DISPLAY 0.680851 (2185 3485);
PAINT MONO (2185 3485);
FORCEPROP 0 LASTPIN (2175 3525) $PN BY18
J 0
(2185 3535);
DISPLAY 0.680851 (2185 3535);
PAINT MONO (2185 3535);
FORCEPROP 0 LASTPIN (2175 3575) $PN CC19
J 0
(2185 3585);
DISPLAY 0.680851 (2185 3585);
PAINT MONO (2185 3585);
FORCEPROP 0 LASTPIN (2175 3625) $PN CD18
J 0
(2185 3635);
DISPLAY 0.680851 (2185 3635);
PAINT MONO (2185 3635);
FORCEPROP 0 LASTPIN (2175 3675) $PN CG19
J 0
(2185 3685);
DISPLAY 0.680851 (2185 3685);
PAINT MONO (2185 3685);
FORCEPROP 0 LASTPIN (2175 3725) $PN CH18
J 0
(2185 3735);
DISPLAY 0.680851 (2185 3735);
PAINT MONO (2185 3735);
FORCEPROP 0 LASTPIN (2175 3775) $PN CL19
J 0
(2185 3785);
DISPLAY 0.680851 (2185 3785);
PAINT MONO (2185 3785);
FORCEPROP 0 LASTPIN (2175 3825) $PN CM18
J 0
(2185 3835);
DISPLAY 0.680851 (2185 3835);
PAINT MONO (2185 3835);
FORCEPROP 1 LAST CDS_LMAN_SYM_OUTLINE -1050,550,1050,-550
J 0
(975 3425);
DISPLAY 0.468085 (975 3425);
PAINT GREEN (975 3425);
DISPLAY INVISIBLE (975 3425);
FORCEPROP 1 LAST NEEDS_NO_SIZE TRUE
J 0
(975 3425);
DISPLAY 0.723404 (975 3425);
PAINT GREEN (975 3425);
DISPLAY INVISIBLE (975 3425);
FORCEPROP 2 LAST CDS_LIB pure_quanta
J 0
(975 3425);
DISPLAY INVISIBLE (975 3425);
FORCEPROP 2 LAST CDS_LOCATION U1
J 0
(-75 4300);
DISPLAY 1.021277 (-75 4300);
DISPLAY INVISIBLE (-75 4300);
FORCEPROP 0 LAST $SEC 16
J 0
(-75 4300);
DISPLAY 0.680851 (-75 4300);
PAINT MONO (-75 4300);
DISPLAY INVISIBLE (-75 4300);
FORCEPROP 2 LAST CDS_SEC 16
J 0
(-75 4300);
DISPLAY 1.021277 (-75 4300);
DISPLAY INVISIBLE (-75 4300);
FORCEPROP 1 LAST PATH I20
J 0
(975 3425);
DISPLAY 0.723404 (975 3425);
PAINT GREEN (975 3425);
DISPLAY INVISIBLE (975 3425);
FORCEADD TAP..1
(2650 3025);
FORCEPROP 3 LASTPIN (2600 3025) SIG_NAME TP_DMI_CPU1_PCH_TX_DN<0>
J 0
(2610 3035);
DISPLAY 0.659574 (2610 3035);
PAINT MONO (2610 3035);
DISPLAY INVISIBLE (2610 3035);
FORCEPROP 1 LASTPIN (2600 3025) BN 0
J 0
(2588 3033);
DISPLAY 0.680851 (2588 3033);
PAINT GREEN (2588 3033);
FORCEPROP 2 LAST CDS_LIB standard
J 0
(2650 3025);
DISPLAY INVISIBLE (2650 3025);
FORCEPROP 1 LAST BODY_TYPE PLUMBING
J 0
(2650 3075);
DISPLAY 0.872340 (2650 3075);
PAINT GREEN (2650 3075);
DISPLAY INVISIBLE (2650 3075);
FORCEPROP 1 LAST HDL_TAP TRUE
J 0
(2975 2900);
DISPLAY 0.872340 (2975 2900);
DISPLAY INVISIBLE (2975 2900);
FORCEPROP 1 LAST PATH I21
J 0
(2648 3025);
DISPLAY 0.872340 (2648 3025);
PAINT GREEN (2648 3025);
DISPLAY INVISIBLE (2648 3025);
FORCEADD TAP..1
(2650 3125);
FORCEPROP 3 LASTPIN (2600 3125) SIG_NAME TP_DMI_CPU1_PCH_TX_DN<2>
J 0
(2610 3135);
DISPLAY 0.659574 (2610 3135);
PAINT MONO (2610 3135);
DISPLAY INVISIBLE (2610 3135);
FORCEPROP 1 LASTPIN (2600 3125) BN 2
J 0
(2588 3133);
DISPLAY 0.680851 (2588 3133);
PAINT GREEN (2588 3133);
FORCEPROP 2 LAST CDS_LIB standard
J 0
(2650 3125);
DISPLAY INVISIBLE (2650 3125);
FORCEPROP 1 LAST BODY_TYPE PLUMBING
J 0
(2650 3175);
DISPLAY 0.872340 (2650 3175);
PAINT GREEN (2650 3175);
DISPLAY INVISIBLE (2650 3175);
FORCEPROP 1 LAST HDL_TAP TRUE
J 0
(2975 3000);
DISPLAY 0.872340 (2975 3000);
DISPLAY INVISIBLE (2975 3000);
FORCEPROP 1 LAST PATH I22
J 0
(2648 3125);
DISPLAY 0.872340 (2648 3125);
PAINT GREEN (2648 3125);
DISPLAY INVISIBLE (2648 3125);
FORCEADD TAP..1
(2650 3075);
FORCEPROP 3 LASTPIN (2600 3075) SIG_NAME TP_DMI_CPU1_PCH_TX_DN<1>
J 0
(2610 3085);
DISPLAY 0.659574 (2610 3085);
PAINT MONO (2610 3085);
DISPLAY INVISIBLE (2610 3085);
FORCEPROP 1 LASTPIN (2600 3075) BN 1
J 0
(2588 3083);
DISPLAY 0.680851 (2588 3083);
PAINT GREEN (2588 3083);
FORCEPROP 2 LAST CDS_LIB standard
J 0
(2650 3075);
DISPLAY INVISIBLE (2650 3075);
FORCEPROP 1 LAST BODY_TYPE PLUMBING
J 0
(2650 3125);
DISPLAY 0.872340 (2650 3125);
PAINT GREEN (2650 3125);
DISPLAY INVISIBLE (2650 3125);
FORCEPROP 1 LAST HDL_TAP TRUE
J 0
(2975 2950);
DISPLAY 0.872340 (2975 2950);
DISPLAY INVISIBLE (2975 2950);
FORCEPROP 1 LAST PATH I23
J 0
(2648 3075);
DISPLAY 0.872340 (2648 3075);
PAINT GREEN (2648 3075);
DISPLAY INVISIBLE (2648 3075);
FORCEADD TAP..1
(2650 3175);
FORCEPROP 3 LASTPIN (2600 3175) SIG_NAME TP_DMI_CPU1_PCH_TX_DN<3>
J 0
(2610 3185);
DISPLAY 0.659574 (2610 3185);
PAINT MONO (2610 3185);
DISPLAY INVISIBLE (2610 3185);
FORCEPROP 1 LASTPIN (2600 3175) BN 3
J 0
(2588 3183);
DISPLAY 0.680851 (2588 3183);
PAINT GREEN (2588 3183);
FORCEPROP 2 LAST CDS_LIB standard
J 0
(2650 3175);
DISPLAY INVISIBLE (2650 3175);
FORCEPROP 1 LAST BODY_TYPE PLUMBING
J 0
(2650 3225);
DISPLAY 0.872340 (2650 3225);
PAINT GREEN (2650 3225);
DISPLAY INVISIBLE (2650 3225);
FORCEPROP 1 LAST HDL_TAP TRUE
J 0
(2975 3050);
DISPLAY 0.872340 (2975 3050);
DISPLAY INVISIBLE (2975 3050);
FORCEPROP 1 LAST PATH I24
J 0
(2648 3175);
DISPLAY 0.872340 (2648 3175);
PAINT GREEN (2648 3175);
DISPLAY INVISIBLE (2648 3175);
FORCEADD TAP..1
(2650 3225);
FORCEPROP 3 LASTPIN (2600 3225) SIG_NAME TP_DMI_CPU1_PCH_TX_DN<4>
J 0
(2610 3235);
DISPLAY 0.659574 (2610 3235);
PAINT MONO (2610 3235);
DISPLAY INVISIBLE (2610 3235);
FORCEPROP 1 LASTPIN (2600 3225) BN 4
J 0
(2588 3233);
DISPLAY 0.680851 (2588 3233);
PAINT GREEN (2588 3233);
FORCEPROP 2 LAST CDS_LIB standard
J 0
(2650 3225);
DISPLAY INVISIBLE (2650 3225);
FORCEPROP 1 LAST BODY_TYPE PLUMBING
J 0
(2650 3275);
DISPLAY 0.872340 (2650 3275);
PAINT GREEN (2650 3275);
DISPLAY INVISIBLE (2650 3275);
FORCEPROP 1 LAST HDL_TAP TRUE
J 0
(2975 3100);
DISPLAY 0.872340 (2975 3100);
DISPLAY INVISIBLE (2975 3100);
FORCEPROP 1 LAST PATH I25
J 0
(2648 3225);
DISPLAY 0.872340 (2648 3225);
PAINT GREEN (2648 3225);
DISPLAY INVISIBLE (2648 3225);
FORCEADD TAP..1
(2650 3275);
FORCEPROP 3 LASTPIN (2600 3275) SIG_NAME TP_DMI_CPU1_PCH_TX_DN<5>
J 0
(2610 3285);
DISPLAY 0.659574 (2610 3285);
PAINT MONO (2610 3285);
DISPLAY INVISIBLE (2610 3285);
FORCEPROP 1 LASTPIN (2600 3275) BN 5
J 0
(2588 3283);
DISPLAY 0.680851 (2588 3283);
PAINT GREEN (2588 3283);
FORCEPROP 2 LAST CDS_LIB standard
J 0
(2650 3275);
DISPLAY INVISIBLE (2650 3275);
FORCEPROP 1 LAST BODY_TYPE PLUMBING
J 0
(2650 3325);
DISPLAY 0.872340 (2650 3325);
PAINT GREEN (2650 3325);
DISPLAY INVISIBLE (2650 3325);
FORCEPROP 1 LAST HDL_TAP TRUE
J 0
(2975 3150);
DISPLAY 0.872340 (2975 3150);
DISPLAY INVISIBLE (2975 3150);
FORCEPROP 1 LAST PATH I26
J 0
(2648 3275);
DISPLAY 0.872340 (2648 3275);
PAINT GREEN (2648 3275);
DISPLAY INVISIBLE (2648 3275);
FORCEADD TAP..1
(2650 3375);
FORCEPROP 3 LASTPIN (2600 3375) SIG_NAME TP_DMI_CPU1_PCH_TX_DN<7>
J 0
(2610 3385);
DISPLAY 0.659574 (2610 3385);
PAINT MONO (2610 3385);
DISPLAY INVISIBLE (2610 3385);
FORCEPROP 1 LASTPIN (2600 3375) BN 7
J 0
(2588 3383);
DISPLAY 0.680851 (2588 3383);
PAINT GREEN (2588 3383);
FORCEPROP 2 LAST CDS_LIB standard
J 0
(2650 3375);
DISPLAY INVISIBLE (2650 3375);
FORCEPROP 1 LAST BODY_TYPE PLUMBING
J 0
(2650 3425);
DISPLAY 0.872340 (2650 3425);
PAINT GREEN (2650 3425);
DISPLAY INVISIBLE (2650 3425);
FORCEPROP 1 LAST HDL_TAP TRUE
J 0
(2975 3250);
DISPLAY 0.872340 (2975 3250);
DISPLAY INVISIBLE (2975 3250);
FORCEPROP 1 LAST PATH I27
J 0
(2648 3375);
DISPLAY 0.872340 (2648 3375);
PAINT GREEN (2648 3375);
DISPLAY INVISIBLE (2648 3375);
FORCEADD TAP..1
(2650 3325);
FORCEPROP 3 LASTPIN (2600 3325) SIG_NAME TP_DMI_CPU1_PCH_TX_DN<6>
J 0
(2610 3335);
DISPLAY 0.659574 (2610 3335);
PAINT MONO (2610 3335);
DISPLAY INVISIBLE (2610 3335);
FORCEPROP 1 LASTPIN (2600 3325) BN 6
J 0
(2588 3333);
DISPLAY 0.680851 (2588 3333);
PAINT GREEN (2588 3333);
FORCEPROP 2 LAST CDS_LIB standard
J 0
(2650 3325);
DISPLAY INVISIBLE (2650 3325);
FORCEPROP 1 LAST BODY_TYPE PLUMBING
J 0
(2650 3375);
DISPLAY 0.872340 (2650 3375);
PAINT GREEN (2650 3375);
DISPLAY INVISIBLE (2650 3375);
FORCEPROP 1 LAST HDL_TAP TRUE
J 0
(2975 3200);
DISPLAY 0.872340 (2975 3200);
DISPLAY INVISIBLE (2975 3200);
FORCEPROP 1 LAST PATH I28
J 0
(2648 3325);
DISPLAY 0.872340 (2648 3325);
PAINT GREEN (2648 3325);
DISPLAY INVISIBLE (2648 3325);
FORCEADD TAP..1
(2650 3525);
FORCEPROP 3 LASTPIN (2600 3525) SIG_NAME TP_DMI_CPU1_PCH_TX_DP<1>
J 0
(2610 3535);
DISPLAY 0.659574 (2610 3535);
PAINT MONO (2610 3535);
DISPLAY INVISIBLE (2610 3535);
FORCEPROP 1 LASTPIN (2600 3525) BN 1
J 0
(2588 3533);
DISPLAY 0.680851 (2588 3533);
PAINT GREEN (2588 3533);
FORCEPROP 2 LAST CDS_LIB standard
J 0
(2650 3525);
DISPLAY INVISIBLE (2650 3525);
FORCEPROP 1 LAST BODY_TYPE PLUMBING
J 0
(2650 3575);
DISPLAY 0.872340 (2650 3575);
PAINT GREEN (2650 3575);
DISPLAY INVISIBLE (2650 3575);
FORCEPROP 1 LAST HDL_TAP TRUE
J 0
(2975 3400);
DISPLAY 0.872340 (2975 3400);
DISPLAY INVISIBLE (2975 3400);
FORCEPROP 1 LAST PATH I29
J 0
(2648 3525);
DISPLAY 0.872340 (2648 3525);
PAINT GREEN (2648 3525);
DISPLAY INVISIBLE (2648 3525);
FORCEADD TAP..1
(2650 3475);
FORCEPROP 3 LASTPIN (2600 3475) SIG_NAME TP_DMI_CPU1_PCH_TX_DP<0>
J 0
(2610 3485);
DISPLAY 0.659574 (2610 3485);
PAINT MONO (2610 3485);
DISPLAY INVISIBLE (2610 3485);
FORCEPROP 1 LASTPIN (2600 3475) BN 0
J 0
(2588 3483);
DISPLAY 0.680851 (2588 3483);
PAINT GREEN (2588 3483);
FORCEPROP 2 LAST CDS_LIB standard
J 0
(2650 3475);
DISPLAY INVISIBLE (2650 3475);
FORCEPROP 1 LAST BODY_TYPE PLUMBING
J 0
(2650 3525);
DISPLAY 0.872340 (2650 3525);
PAINT GREEN (2650 3525);
DISPLAY INVISIBLE (2650 3525);
FORCEPROP 1 LAST HDL_TAP TRUE
J 0
(2975 3350);
DISPLAY 0.872340 (2975 3350);
DISPLAY INVISIBLE (2975 3350);
FORCEPROP 1 LAST PATH I30
J 0
(2648 3475);
DISPLAY 0.872340 (2648 3475);
PAINT GREEN (2648 3475);
DISPLAY INVISIBLE (2648 3475);
FORCEADD TAP..1
(2650 3625);
FORCEPROP 3 LASTPIN (2600 3625) SIG_NAME TP_DMI_CPU1_PCH_TX_DP<3>
J 0
(2610 3635);
DISPLAY 0.659574 (2610 3635);
PAINT MONO (2610 3635);
DISPLAY INVISIBLE (2610 3635);
FORCEPROP 1 LASTPIN (2600 3625) BN 3
J 0
(2588 3633);
DISPLAY 0.680851 (2588 3633);
PAINT GREEN (2588 3633);
FORCEPROP 2 LAST CDS_LIB standard
J 0
(2650 3625);
DISPLAY INVISIBLE (2650 3625);
FORCEPROP 1 LAST BODY_TYPE PLUMBING
J 0
(2650 3675);
DISPLAY 0.872340 (2650 3675);
PAINT GREEN (2650 3675);
DISPLAY INVISIBLE (2650 3675);
FORCEPROP 1 LAST HDL_TAP TRUE
J 0
(2975 3500);
DISPLAY 0.872340 (2975 3500);
DISPLAY INVISIBLE (2975 3500);
FORCEPROP 1 LAST PATH I31
J 0
(2648 3625);
DISPLAY 0.872340 (2648 3625);
PAINT GREEN (2648 3625);
DISPLAY INVISIBLE (2648 3625);
FORCEADD TAP..1
(2650 3575);
FORCEPROP 3 LASTPIN (2600 3575) SIG_NAME TP_DMI_CPU1_PCH_TX_DP<2>
J 0
(2610 3585);
DISPLAY 0.659574 (2610 3585);
PAINT MONO (2610 3585);
DISPLAY INVISIBLE (2610 3585);
FORCEPROP 1 LASTPIN (2600 3575) BN 2
J 0
(2588 3583);
DISPLAY 0.680851 (2588 3583);
PAINT GREEN (2588 3583);
FORCEPROP 2 LAST CDS_LIB standard
J 0
(2650 3575);
DISPLAY INVISIBLE (2650 3575);
FORCEPROP 1 LAST BODY_TYPE PLUMBING
J 0
(2650 3625);
DISPLAY 0.872340 (2650 3625);
PAINT GREEN (2650 3625);
DISPLAY INVISIBLE (2650 3625);
FORCEPROP 1 LAST HDL_TAP TRUE
J 0
(2975 3450);
DISPLAY 0.872340 (2975 3450);
DISPLAY INVISIBLE (2975 3450);
FORCEPROP 1 LAST PATH I32
J 0
(2648 3575);
DISPLAY 0.872340 (2648 3575);
PAINT GREEN (2648 3575);
DISPLAY INVISIBLE (2648 3575);
FORCEADD TAP..1
(2650 3775);
FORCEPROP 3 LASTPIN (2600 3775) SIG_NAME TP_DMI_CPU1_PCH_TX_DP<6>
J 0
(2610 3785);
DISPLAY 0.659574 (2610 3785);
PAINT MONO (2610 3785);
DISPLAY INVISIBLE (2610 3785);
FORCEPROP 1 LASTPIN (2600 3775) BN 6
J 0
(2588 3783);
DISPLAY 0.680851 (2588 3783);
PAINT GREEN (2588 3783);
FORCEPROP 2 LAST CDS_LIB standard
J 0
(2650 3775);
DISPLAY INVISIBLE (2650 3775);
FORCEPROP 1 LAST BODY_TYPE PLUMBING
J 0
(2650 3825);
DISPLAY 0.872340 (2650 3825);
PAINT GREEN (2650 3825);
DISPLAY INVISIBLE (2650 3825);
FORCEPROP 1 LAST HDL_TAP TRUE
J 0
(2975 3650);
DISPLAY 0.872340 (2975 3650);
DISPLAY INVISIBLE (2975 3650);
FORCEPROP 1 LAST PATH I33
J 0
(2648 3775);
DISPLAY 0.872340 (2648 3775);
PAINT GREEN (2648 3775);
DISPLAY INVISIBLE (2648 3775);
FORCEADD TAP..1
(2650 3725);
FORCEPROP 3 LASTPIN (2600 3725) SIG_NAME TP_DMI_CPU1_PCH_TX_DP<5>
J 0
(2610 3735);
DISPLAY 0.659574 (2610 3735);
PAINT MONO (2610 3735);
DISPLAY INVISIBLE (2610 3735);
FORCEPROP 1 LASTPIN (2600 3725) BN 5
J 0
(2588 3733);
DISPLAY 0.680851 (2588 3733);
PAINT GREEN (2588 3733);
FORCEPROP 2 LAST CDS_LIB standard
J 0
(2650 3725);
DISPLAY INVISIBLE (2650 3725);
FORCEPROP 1 LAST BODY_TYPE PLUMBING
J 0
(2650 3775);
DISPLAY 0.872340 (2650 3775);
PAINT GREEN (2650 3775);
DISPLAY INVISIBLE (2650 3775);
FORCEPROP 1 LAST HDL_TAP TRUE
J 0
(2975 3600);
DISPLAY 0.872340 (2975 3600);
DISPLAY INVISIBLE (2975 3600);
FORCEPROP 1 LAST PATH I34
J 0
(2648 3725);
DISPLAY 0.872340 (2648 3725);
PAINT GREEN (2648 3725);
DISPLAY INVISIBLE (2648 3725);
FORCEADD TAP..1
(2650 3675);
FORCEPROP 3 LASTPIN (2600 3675) SIG_NAME TP_DMI_CPU1_PCH_TX_DP<4>
J 0
(2610 3685);
DISPLAY 0.659574 (2610 3685);
PAINT MONO (2610 3685);
DISPLAY INVISIBLE (2610 3685);
FORCEPROP 1 LASTPIN (2600 3675) BN 4
J 0
(2588 3683);
DISPLAY 0.680851 (2588 3683);
PAINT GREEN (2588 3683);
FORCEPROP 2 LAST CDS_LIB standard
J 0
(2650 3675);
DISPLAY INVISIBLE (2650 3675);
FORCEPROP 1 LAST BODY_TYPE PLUMBING
J 0
(2650 3725);
DISPLAY 0.872340 (2650 3725);
PAINT GREEN (2650 3725);
DISPLAY INVISIBLE (2650 3725);
FORCEPROP 1 LAST HDL_TAP TRUE
J 0
(2975 3550);
DISPLAY 0.872340 (2975 3550);
DISPLAY INVISIBLE (2975 3550);
FORCEPROP 1 LAST PATH I35
J 0
(2648 3675);
DISPLAY 0.872340 (2648 3675);
PAINT GREEN (2648 3675);
DISPLAY INVISIBLE (2648 3675);
FORCEADD TAP..1
(2650 3825);
FORCEPROP 3 LASTPIN (2600 3825) SIG_NAME TP_DMI_CPU1_PCH_TX_DP<7>
J 0
(2610 3835);
DISPLAY 0.659574 (2610 3835);
PAINT MONO (2610 3835);
DISPLAY INVISIBLE (2610 3835);
FORCEPROP 1 LASTPIN (2600 3825) BN 7
J 0
(2588 3833);
DISPLAY 0.680851 (2588 3833);
PAINT GREEN (2588 3833);
FORCEPROP 2 LAST CDS_LIB standard
J 0
(2650 3825);
DISPLAY INVISIBLE (2650 3825);
FORCEPROP 1 LAST BODY_TYPE PLUMBING
J 0
(2650 3875);
DISPLAY 0.872340 (2650 3875);
PAINT GREEN (2650 3875);
DISPLAY INVISIBLE (2650 3875);
FORCEPROP 1 LAST HDL_TAP TRUE
J 0
(2975 3700);
DISPLAY 0.872340 (2975 3700);
DISPLAY INVISIBLE (2975 3700);
FORCEPROP 1 LAST PATH I36
J 0
(2648 3825);
DISPLAY 0.872340 (2648 3825);
PAINT GREEN (2648 3825);
DISPLAY INVISIBLE (2648 3825);
FORCEADD TAP..1
R 2
(-725 3125);
FORCEPROP 3 LASTPIN (-675 3125) SIG_NAME TP_DMI_CPU1_PCH_RX_C_DN<2>
J 0
(-665 3135);
DISPLAY 0.659574 (-665 3135);
PAINT MONO (-665 3135);
DISPLAY INVISIBLE (-665 3135);
FORCEPROP 1 LASTPIN (-675 3125) BN 2
J 2
(-663 3133);
DISPLAY 0.680851 (-663 3133);
PAINT GREEN (-663 3133);
FORCEPROP 2 LAST CDS_LIB standard
J 0
(-725 3125);
DISPLAY INVISIBLE (-725 3125);
FORCEPROP 1 LAST BODY_TYPE PLUMBING
J 2
(-725 3175);
DISPLAY 0.872340 (-725 3175);
PAINT GREEN (-725 3175);
DISPLAY INVISIBLE (-725 3175);
FORCEPROP 1 LAST HDL_TAP TRUE
J 2
(-1050 3000);
DISPLAY 0.872340 (-1050 3000);
DISPLAY INVISIBLE (-1050 3000);
FORCEPROP 1 LAST PATH I4
J 2
(-723 3125);
DISPLAY 0.872340 (-723 3125);
PAINT GREEN (-723 3125);
DISPLAY INVISIBLE (-723 3125);
FORCEADD TAP..1
R 2
(-725 3075);
FORCEPROP 3 LASTPIN (-675 3075) SIG_NAME TP_DMI_CPU1_PCH_RX_C_DN<1>
J 0
(-665 3085);
DISPLAY 0.659574 (-665 3085);
PAINT MONO (-665 3085);
DISPLAY INVISIBLE (-665 3085);
FORCEPROP 1 LASTPIN (-675 3075) BN 1
J 2
(-663 3083);
DISPLAY 0.680851 (-663 3083);
PAINT GREEN (-663 3083);
FORCEPROP 2 LAST CDS_LIB standard
J 0
(-725 3075);
DISPLAY INVISIBLE (-725 3075);
FORCEPROP 1 LAST BODY_TYPE PLUMBING
J 2
(-725 3125);
DISPLAY 0.872340 (-725 3125);
PAINT GREEN (-725 3125);
DISPLAY INVISIBLE (-725 3125);
FORCEPROP 1 LAST HDL_TAP TRUE
J 2
(-1050 2950);
DISPLAY 0.872340 (-1050 2950);
DISPLAY INVISIBLE (-1050 2950);
FORCEPROP 1 LAST PATH I5
J 2
(-723 3075);
DISPLAY 0.872340 (-723 3075);
PAINT GREEN (-723 3075);
DISPLAY INVISIBLE (-723 3075);
FORCEADD TAP..1
R 2
(-725 3025);
FORCEPROP 3 LASTPIN (-675 3025) SIG_NAME TP_DMI_CPU1_PCH_RX_C_DN<0>
J 0
(-665 3035);
DISPLAY 0.659574 (-665 3035);
PAINT MONO (-665 3035);
DISPLAY INVISIBLE (-665 3035);
FORCEPROP 1 LASTPIN (-675 3025) BN 0
J 2
(-663 3033);
DISPLAY 0.680851 (-663 3033);
PAINT GREEN (-663 3033);
FORCEPROP 2 LAST CDS_LIB standard
J 0
(-725 3025);
DISPLAY INVISIBLE (-725 3025);
FORCEPROP 1 LAST BODY_TYPE PLUMBING
J 2
(-725 3075);
DISPLAY 0.872340 (-725 3075);
PAINT GREEN (-725 3075);
DISPLAY INVISIBLE (-725 3075);
FORCEPROP 1 LAST HDL_TAP TRUE
J 2
(-1050 2900);
DISPLAY 0.872340 (-1050 2900);
DISPLAY INVISIBLE (-1050 2900);
FORCEPROP 1 LAST PATH I6
J 2
(-723 3025);
DISPLAY 0.872340 (-723 3025);
PAINT GREEN (-723 3025);
DISPLAY INVISIBLE (-723 3025);
FORCEADD TAP..1
R 2
(-725 3175);
FORCEPROP 3 LASTPIN (-675 3175) SIG_NAME TP_DMI_CPU1_PCH_RX_C_DN<3>
J 0
(-665 3185);
DISPLAY 0.659574 (-665 3185);
PAINT MONO (-665 3185);
DISPLAY INVISIBLE (-665 3185);
FORCEPROP 1 LASTPIN (-675 3175) BN 3
J 2
(-663 3183);
DISPLAY 0.680851 (-663 3183);
PAINT GREEN (-663 3183);
FORCEPROP 2 LAST CDS_LIB standard
J 0
(-725 3175);
DISPLAY INVISIBLE (-725 3175);
FORCEPROP 1 LAST BODY_TYPE PLUMBING
J 2
(-725 3225);
DISPLAY 0.872340 (-725 3225);
PAINT GREEN (-725 3225);
DISPLAY INVISIBLE (-725 3225);
FORCEPROP 1 LAST HDL_TAP TRUE
J 2
(-1050 3050);
DISPLAY 0.872340 (-1050 3050);
DISPLAY INVISIBLE (-1050 3050);
FORCEPROP 1 LAST PATH I7
J 2
(-723 3175);
DISPLAY 0.872340 (-723 3175);
PAINT GREEN (-723 3175);
DISPLAY INVISIBLE (-723 3175);
FORCEADD TAP..1
R 2
(-725 3225);
FORCEPROP 3 LASTPIN (-675 3225) SIG_NAME TP_DMI_CPU1_PCH_RX_C_DN<4>
J 0
(-665 3235);
DISPLAY 0.659574 (-665 3235);
PAINT MONO (-665 3235);
DISPLAY INVISIBLE (-665 3235);
FORCEPROP 1 LASTPIN (-675 3225) BN 4
J 2
(-663 3233);
DISPLAY 0.680851 (-663 3233);
PAINT GREEN (-663 3233);
FORCEPROP 2 LAST CDS_LIB standard
J 0
(-725 3225);
DISPLAY INVISIBLE (-725 3225);
FORCEPROP 1 LAST BODY_TYPE PLUMBING
J 2
(-725 3275);
DISPLAY 0.872340 (-725 3275);
PAINT GREEN (-725 3275);
DISPLAY INVISIBLE (-725 3275);
FORCEPROP 1 LAST HDL_TAP TRUE
J 2
(-1050 3100);
DISPLAY 0.872340 (-1050 3100);
DISPLAY INVISIBLE (-1050 3100);
FORCEPROP 1 LAST PATH I8
J 2
(-723 3225);
DISPLAY 0.872340 (-723 3225);
PAINT GREEN (-723 3225);
DISPLAY INVISIBLE (-723 3225);
FORCEADD TAP..1
R 2
(-725 3375);
FORCEPROP 3 LASTPIN (-675 3375) SIG_NAME TP_DMI_CPU1_PCH_RX_C_DN<7>
J 0
(-665 3385);
DISPLAY 0.659574 (-665 3385);
PAINT MONO (-665 3385);
DISPLAY INVISIBLE (-665 3385);
FORCEPROP 1 LASTPIN (-675 3375) BN 7
J 2
(-663 3383);
DISPLAY 0.680851 (-663 3383);
PAINT GREEN (-663 3383);
FORCEPROP 2 LAST CDS_LIB standard
J 0
(-725 3375);
DISPLAY INVISIBLE (-725 3375);
FORCEPROP 1 LAST BODY_TYPE PLUMBING
J 2
(-725 3425);
DISPLAY 0.872340 (-725 3425);
PAINT GREEN (-725 3425);
DISPLAY INVISIBLE (-725 3425);
FORCEPROP 1 LAST HDL_TAP TRUE
J 2
(-1050 3250);
DISPLAY 0.872340 (-1050 3250);
DISPLAY INVISIBLE (-1050 3250);
FORCEPROP 1 LAST PATH I9
J 2
(-723 3375);
DISPLAY 0.872340 (-723 3375);
PAINT GREEN (-723 3375);
DISPLAY INVISIBLE (-723 3375);
FORCEADD QUANTA_TITLE_BLOCK_C..1
(5575 -1675);
FORCEPROP 0 LAST CDS_CON_LAST_MODIFIED Fri Aug 25 14:00:41 2023
J 0
(3690 -1660);
PAINT MONO (3690 -1660);
DISPLAY INVISIBLE (3690 -1660);
FORCEPROP 1 LAST CUSTOM_TXT_CDS <CON_LAST_MODIFIED>
J 0
(3690 -1660);
DISPLAY 0.978723 (3690 -1660);
FORCEPROP 2 LAST CUSTOM_TXT_CDS <XR_PAGE_TITLE>
J 0
(-2315 3575);
DISPLAY 0.638298 (-2315 3575);
PAINT PINK (-2315 3575);
DISPLAY INVISIBLE (-2315 3575);
FORCEPROP 2 LAST CUSTOM_TXT_CDS <Q_NUMBER>
J 0
(4172 -1572);
DISPLAY 1.212766 (4172 -1572);
FORCEPROP 1 LAST CUSTOM_TXT_CDS <NAME_2>
J 0
(2400 -1625);
FORCEPROP 1 LAST CUSTOM_TXT_CDS <NAME_1>
J 0
(2400 -1500);
FORCEPROP 1 LAST CUSTOM_TXT_CDS <Q_PROJ>
J 0
(3193 -1573);
DISPLAY 1.212766 (3193 -1573);
FORCEPROP 1 LAST CUSTOM_TXT_CDS <Q_REV>
J 0
(5391 -1572);
DISPLAY 1.212766 (5391 -1572);
FORCEPROP 1 LAST CUSTOM_TXT_CDS <CON_PAGE_NUM> OF <CON_TOTAL_PAGES>
J 0
(5129 -1657);
DISPLAY 0.978723 (5129 -1657);
FORCEPROP 1 LAST Q_TITLE SPR CPU1 - DMI (16 OF 30)
J 0
(-3791 -1649);
DISPLAY 1.957447 (-3791 -1649);
PAINT GREEN (-3791 -1649);
FORCEPROP 1 LAST Q_DEPT 
J 1
(1812 -1626);
DISPLAY 1.957447 (1812 -1626);
PAINT GREEN (1812 -1626);
FORCEPROP 1 LAST COMMENT_BODY TRUE
J 0
(5587 -1688);
DISPLAY 0.978723 (5587 -1688);
PAINT GREEN (5587 -1688);
DISPLAY INVISIBLE (5587 -1688);
FORCEPROP 2 LAST CDS_XR_PAGE_TITLE CR-59 : @S9S_MB_2U_LIB.S9S_MB_2U(SCH_1):PAGE59
J 0
(-2315 3575);
DISPLAY 0.638298 (-2315 3575);
PAINT PINK (-2315 3575);
DISPLAY INVISIBLE (-2315 3575);
FORCEPROP 2 LAST CDS_LIB pure_quanta
J 0
(5575 -1675);
PAINT MONO (5575 -1675);
DISPLAY INVISIBLE (5575 -1675);
FORCEPROP 1 LAST CDS_LMAN_SYM_OUTLINE -9475,6775,100,-125
J 0
(5575 -1675);
DISPLAY 0.468085 (5575 -1675);
PAINT GREEN (5575 -1675);
DISPLAY INVISIBLE (5575 -1675);
FORCEPROP 2 LAST PAGE_BORDER TRUE
J 0
(-2315 3575);
DISPLAY 0.638298 (-2315 3575);
PAINT PINK (-2315 3575);
DISPLAY INVISIBLE (-2315 3575);
WIRE 17 -1 (2700 3500)(2700 3550);
WIRE 17 -1 (2700 3550)(2700 3600);
WIRE 17 -1 (2700 3600)(2700 3650);
WIRE 17 -1 (2700 3650)(2700 3700);
WIRE 17 -1 (2700 3700)(2700 3750);
WIRE 17 -1 (2700 3750)(2700 3800);
WIRE 17 -1 (2700 3800)(2700 3850);
WIRE 17 -1 (2700 3850)(3700 3850);
FORCEPROP 2 LAST SIG_NAME TP_DMI_CPU1_PCH_TX_DP<7:0>
J 0
(2790 3860);
DISPLAY 0.680851 (2790 3860);
PAINT WHITE (2790 3860);
WIRE 17 -1 (2700 3050)(2700 3100);
WIRE 17 -1 (2700 3100)(2700 3150);
WIRE 17 -1 (2700 3150)(2700 3200);
WIRE 17 -1 (2700 3200)(2700 3250);
WIRE 17 -1 (2700 3250)(2700 3300);
WIRE 17 -1 (2700 3300)(2700 3350);
WIRE 17 -1 (2700 3350)(2700 3400);
WIRE 17 -1 (2700 3400)(3700 3400);
FORCEPROP 2 LAST SIG_NAME TP_DMI_CPU1_PCH_TX_DN<7:0>
J 0
(2790 3410);
DISPLAY 0.680851 (2790 3410);
PAINT WHITE (2790 3410);
WIRE 17 -1 (-775 3500)(-775 3550);
WIRE 17 -1 (-775 3550)(-775 3600);
WIRE 17 -1 (-775 3600)(-775 3650);
WIRE 17 -1 (-775 3650)(-775 3700);
WIRE 17 -1 (-775 3700)(-775 3750);
WIRE 17 -1 (-775 3750)(-775 3800);
WIRE 17 -1 (-775 3800)(-775 3850);
WIRE 17 -1 (-1925 3850)(-775 3850);
FORCEPROP 2 LAST SIG_NAME TP_DMI_CPU1_PCH_RX_C_DP<7:0>
J 0
(-1810 3860);
DISPLAY 0.680851 (-1810 3860);
PAINT WHITE (-1810 3860);
WIRE 17 -1 (-775 3050)(-775 3100);
WIRE 17 -1 (-775 3100)(-775 3150);
WIRE 17 -1 (-775 3150)(-775 3200);
WIRE 17 -1 (-775 3200)(-775 3250);
WIRE 17 -1 (-775 3250)(-775 3300);
WIRE 17 -1 (-775 3300)(-775 3350);
WIRE 17 -1 (-775 3350)(-775 3400);
WIRE 17 -1 (-1925 3400)(-775 3400);
FORCEPROP 2 LAST SIG_NAME TP_DMI_CPU1_PCH_RX_C_DN<7:0>
J 0
(-1810 3410);
DISPLAY 0.680851 (-1810 3410);
PAINT WHITE (-1810 3410);
WIRE 16 -1 (-675 3375)(-225 3375);
WIRE 16 -1 (-675 3325)(-225 3325);
WIRE 16 -1 (-675 3275)(-225 3275);
WIRE 16 -1 (-675 3225)(-225 3225);
WIRE 16 -1 (-675 3175)(-225 3175);
WIRE 16 -1 (-675 3125)(-225 3125);
WIRE 16 -1 (-675 3075)(-225 3075);
WIRE 16 -1 (-675 3025)(-225 3025);
WIRE 16 -1 (-675 3825)(-225 3825);
WIRE 16 -1 (-675 3775)(-225 3775);
WIRE 16 -1 (-675 3725)(-225 3725);
WIRE 16 -1 (-675 3675)(-225 3675);
WIRE 16 -1 (-675 3625)(-225 3625);
WIRE 16 -1 (-675 3575)(-225 3575);
WIRE 16 -1 (-675 3525)(-225 3525);
WIRE 16 -1 (-675 3475)(-225 3475);
WIRE 16 -1 (2175 3375)(2600 3375);
WIRE 16 -1 (2175 3325)(2600 3325);
WIRE 16 -1 (2175 3275)(2600 3275);
WIRE 16 -1 (2175 3225)(2600 3225);
WIRE 16 -1 (2175 3175)(2600 3175);
WIRE 16 -1 (2175 3125)(2600 3125);
WIRE 16 -1 (2175 3075)(2600 3075);
WIRE 16 -1 (2175 3025)(2600 3025);
WIRE 16 -1 (2175 3825)(2600 3825);
WIRE 16 -1 (2175 3775)(2600 3775);
WIRE 16 -1 (2175 3725)(2600 3725);
WIRE 16 -1 (2175 3675)(2600 3675);
WIRE 16 -1 (2175 3625)(2600 3625);
WIRE 16 -1 (2175 3575)(2600 3575);
WIRE 16 -1 (2175 3525)(2600 3525);
WIRE 16 -1 (2175 3475)(2600 3475);
QUIT
